(kicad_pcb
	(version 20241229)
	(generator "pcbnew")
	(generator_version "9.0")
	(general
		(thickness 1.6642)
		(legacy_teardrops no)
	)
	(paper "A3")
	(title_block
		(title "PolarFire SoM")
		(date "2025-07-22")
		(rev "1.1.4")
		(company "Antmicro Ltd")
		(comment 1 "www.antmicro.com")
		(comment 9 "footprints 403-407 of 470")
	)
	(layers
		(0 "F.Cu" mixed)
		(4 "In1.Cu" power)
		(6 "In2.Cu" signal)
		(8 "In3.Cu" power)
		(10 "In4.Cu" signal)
		(12 "In5.Cu" power)
		(14 "In6.Cu" power)
		(16 "In7.Cu" signal)
		(18 "In8.Cu" power)
		(20 "In9.Cu" signal)
		(22 "In10.Cu" power)
		(24 "In11.Cu" signal)
		(26 "In12.Cu" signal)
		(2 "B.Cu" mixed)
		(9 "F.Adhes" user "F.Adhesive")
		(11 "B.Adhes" user "B.Adhesive")
		(13 "F.Paste" user)
		(15 "B.Paste" user)
		(5 "F.SilkS" user "F.Silkscreen")
		(7 "B.SilkS" user "B.Silkscreen")
		(1 "F.Mask" user)
		(3 "B.Mask" user)
		(17 "Dwgs.User" user "User.Drawings")
		(19 "Cmts.User" user "User.Comments")
		(21 "Eco1.User" user "User.Eco1")
		(23 "Eco2.User" user "User.Eco2")
		(25 "Edge.Cuts" user)
		(27 "Margin" user)
		(31 "F.CrtYd" user "F.Courtyard")
		(29 "B.CrtYd" user "B.Courtyard")
		(35 "F.Fab" user)
		(33 "B.Fab" user)
	)
	(footprint "antmicro-footprints:C_0402_1005Metric"
		(layer "B.Cu")
		(at 198.94 130.85 90)
		(descr "Capacitor SMD 0402")
		(tags "capacitor SMD 0402")
		(property "Reference" "C234"
			(at 5.18 -9.525 90)
			(layer "B.SilkS")
			(effects
				(font
					(size 0.7 0.7)
					(thickness 0.15)
				)
				(justify right bottom mirror)
			)
		)
		(property "Value" "C_100n_0402"
			(at -1.022927 -2.155213 90)
			(layer "B.Fab")
			(hide yes)
			(effects
				(font
					(size 0.7 0.7)
					(thickness 0.15)
				)
				(justify right bottom mirror)
			)
		)
		(property "Datasheet" "https://www.murata.com/products/productdetail?partno=GRM155R61H104KE14%23"
			(at 0 0 90)
			(layer "F.Fab")
			(hide yes)
			(effects
				(font
					(size 1.27 1.27)
					(thickness 0.15)
				)
			)
		)
		(property "Description" "SMD Multilayer Ceramic Capacitor, 0.1 µF, 50 V, 0402 [1005 Metric], ± 10%, X5R, GRM Series"
			(at 0 0 90)
			(layer "F.Fab")
			(hide yes)
			(effects
				(font
					(size 1.27 1.27)
					(thickness 0.15)
				)
			)
		)
		(property "Author" "Antmicro"
			(at 329.79 -68.09 0)
			(layer "B.Fab")
			(hide yes)
			(effects
				(font
					(size 1 1)
					(thickness 0.15)
				)
				(justify mirror)
			)
		)
		(property "Dielectric" "X5R"
			(at 329.79 -68.09 0)
			(layer "B.Fab")
			(hide yes)
			(effects
				(font
					(size 1 1)
					(thickness 0.15)
				)
				(justify mirror)
			)
		)
		(property "License" "Apache-2.0"
			(at 329.79 -68.09 0)
			(layer "B.Fab")
			(hide yes)
			(effects
				(font
					(size 1 1)
					(thickness 0.15)
				)
				(justify mirror)
			)
		)
		(property "MPN" "GRM155R61H104KE14D"
			(at 329.79 -68.09 0)
			(layer "B.Fab")
			(hide yes)
			(effects
				(font
					(size 1 1)
					(thickness 0.15)
				)
				(justify mirror)
			)
		)
		(property "Manufacturer" "Murata"
			(at 329.79 -68.09 0)
			(layer "B.Fab")
			(hide yes)
			(effects
				(font
					(size 1 1)
					(thickness 0.15)
				)
				(justify mirror)
			)
		)
		(property "Public" ""
			(at 329.79 -68.09 0)
			(layer "B.Fab")
			(hide yes)
			(effects
				(font
					(size 1 1)
					(thickness 0.15)
				)
				(justify mirror)
			)
		)
		(property "Val" "100n"
			(at 329.79 -68.09 0)
			(layer "B.Fab")
			(hide yes)
			(effects
				(font
					(size 1 1)
					(thickness 0.15)
				)
				(justify mirror)
			)
		)
		(property "Voltage" "50V"
			(at 329.79 -68.09 0)
			(layer "B.Fab")
			(hide yes)
			(effects
				(font
					(size 1 1)
					(thickness 0.15)
				)
				(justify mirror)
			)
		)
		(sheetname "/FPGA Supply/")
		(sheetfile "fpga-supply.kicad_sch")
		(attr smd)
		(fp_rect
			(start -0.925 0.47)
			(end 0.925 -0.47)
			(stroke
				(width 0.05)
				(type default)
			)
			(fill no)
			(layer "B.CrtYd")
		)
		(fp_line
			(start 0.504 -0.248)
			(end -0.494 -0.248)
			(stroke
				(width 0.15)
				(type solid)
			)
			(layer "B.Fab")
		)
		(fp_line
			(start -0.494 -0.248)
			(end -0.494 0.25)
			(stroke
				(width 0.15)
				(type solid)
			)
			(layer "B.Fab")
		)
		(fp_line
			(start 0.504 0.25)
			(end 0.504 -0.248)
			(stroke
				(width 0.15)
				(type solid)
			)
			(layer "B.Fab")
		)
		(fp_line
			(start -0.494 0.25)
			(end 0.504 0.25)
			(stroke
				(width 0.15)
				(type solid)
			)
			(layer "B.Fab")
		)
		(fp_text user "${REFERENCE}"
			(at -0.939 -4.599 270)
			(layer "B.Fab")
			(effects
				(font
					(size 0.7 0.7)
					(thickness 0.15)
				)
				(justify left bottom mirror)
			)
		)
		(fp_text user "License: Apache-2.0"
			(at -0.939 -5.799 270)
			(layer "B.Fab")
			(effects
				(font
					(size 0.7 0.7)
					(thickness 0.15)
				)
				(justify left bottom mirror)
			)
		)
		(fp_text user "Author: Antmicro"
			(at -0.939 -3.399 270)
			(layer "B.Fab")
			(effects
				(font
					(size 0.7 0.7)
					(thickness 0.15)
				)
				(justify left bottom mirror)
			)
		)
		(pad "1" smd roundrect
			(at -0.48 0 90)
			(size 0.59 0.64)
			(layers "B.Cu" "B.Mask" "B.Paste")
			(roundrect_rratio 0.25)
			(net 417 "GND")
			(pintype "passive")
		)
		(pad "2" smd roundrect
			(at 0.48 0 90)
			(size 0.59 0.64)
			(layers "B.Cu" "B.Mask" "B.Paste")
			(roundrect_rratio 0.25)
			(net 49 "VDDAUX")
			(pintype "passive")
		)
	)
	(footprint "antmicro-footprints:C_0402_1005Metric"
		(layer "B.Cu")
		(at 217.36 117.55 90)
		(descr "Capacitor SMD 0402")
		(tags "capacitor SMD 0402")
		(property "Reference" "C114"
			(at -3.75 0.44 90)
			(layer "B.SilkS")
			(effects
				(font
					(size 0.7 0.7)
					(thickness 0.15)
				)
				(justify right bottom mirror)
			)
		)
		(property "Value" "C_1u_0402"
			(at -1.022927 -2.155213 90)
			(layer "B.Fab")
			(hide yes)
			(effects
				(font
					(size 0.7 0.7)
					(thickness 0.15)
				)
				(justify right bottom mirror)
			)
		)
		(property "Datasheet" "https://product.tdk.com/en/search/capacitor/ceramic/mlcc/info?part_no=C1005X6S1A105K050BC"
			(at 0 0 90)
			(layer "F.Fab")
			(hide yes)
			(effects
				(font
					(size 1.27 1.27)
					(thickness 0.15)
				)
			)
		)
		(property "Description" "SMD Multilayer Ceramic Capacitor, 1 µF, 10 V, 0402 [1005 Metric], ± 10%, X6S, C"
			(at 0 0 90)
			(layer "F.Fab")
			(hide yes)
			(effects
				(font
					(size 1.27 1.27)
					(thickness 0.15)
				)
			)
		)
		(property "Author" "Antmicro"
			(at 334.91 -99.81 0)
			(layer "B.Fab")
			(hide yes)
			(effects
				(font
					(size 1 1)
					(thickness 0.15)
				)
				(justify mirror)
			)
		)
		(property "Dielectric" ""
			(at 334.91 -99.81 0)
			(layer "B.Fab")
			(hide yes)
			(effects
				(font
					(size 1 1)
					(thickness 0.15)
				)
				(justify mirror)
			)
		)
		(property "License" "Apache-2.0"
			(at 334.91 -99.81 0)
			(layer "B.Fab")
			(hide yes)
			(effects
				(font
					(size 1 1)
					(thickness 0.15)
				)
				(justify mirror)
			)
		)
		(property "MPN" "C1005X6S1A105K050BC"
			(at 334.91 -99.81 0)
			(layer "B.Fab")
			(hide yes)
			(effects
				(font
					(size 1 1)
					(thickness 0.15)
				)
				(justify mirror)
			)
		)
		(property "Manufacturer" "TDK"
			(at 334.91 -99.81 0)
			(layer "B.Fab")
			(hide yes)
			(effects
				(font
					(size 1 1)
					(thickness 0.15)
				)
				(justify mirror)
			)
		)
		(property "Public" ""
			(at 334.91 -99.81 0)
			(layer "B.Fab")
			(hide yes)
			(effects
				(font
					(size 1 1)
					(thickness 0.15)
				)
				(justify mirror)
			)
		)
		(property "Val" "1u"
			(at 334.91 -99.81 0)
			(layer "B.Fab")
			(hide yes)
			(effects
				(font
					(size 1 1)
					(thickness 0.15)
				)
				(justify mirror)
			)
		)
		(property "Voltage" ""
			(at 334.91 -99.81 0)
			(layer "B.Fab")
			(hide yes)
			(effects
				(font
					(size 1 1)
					(thickness 0.15)
				)
				(justify mirror)
			)
		)
		(sheetname "/Ethernet/")
		(sheetfile "ethernet.kicad_sch")
		(attr smd)
		(fp_rect
			(start -0.925 0.47)
			(end 0.925 -0.47)
			(stroke
				(width 0.05)
				(type default)
			)
			(fill no)
			(layer "B.CrtYd")
		)
		(fp_line
			(start 0.504 -0.248)
			(end -0.494 -0.248)
			(stroke
				(width 0.15)
				(type solid)
			)
			(layer "B.Fab")
		)
		(fp_line
			(start -0.494 -0.248)
			(end -0.494 0.25)
			(stroke
				(width 0.15)
				(type solid)
			)
			(layer "B.Fab")
		)
		(fp_line
			(start 0.504 0.25)
			(end 0.504 -0.248)
			(stroke
				(width 0.15)
				(type solid)
			)
			(layer "B.Fab")
		)
		(fp_line
			(start -0.494 0.25)
			(end 0.504 0.25)
			(stroke
				(width 0.15)
				(type solid)
			)
			(layer "B.Fab")
		)
		(fp_text user "Author: Antmicro"
			(at -0.939 -3.399 270)
			(layer "B.Fab")
			(effects
				(font
					(size 0.7 0.7)
					(thickness 0.15)
				)
				(justify left bottom mirror)
			)
		)
		(fp_text user "License: Apache-2.0"
			(at -0.939 -5.799 270)
			(layer "B.Fab")
			(effects
				(font
					(size 0.7 0.7)
					(thickness 0.15)
				)
				(justify left bottom mirror)
			)
		)
		(fp_text user "${REFERENCE}"
			(at -0.939 -4.599 270)
			(layer "B.Fab")
			(effects
				(font
					(size 0.7 0.7)
					(thickness 0.15)
				)
				(justify left bottom mirror)
			)
		)
		(pad "1" smd roundrect
			(at -0.48 0 90)
			(size 0.59 0.64)
			(layers "B.Cu" "B.Mask" "B.Paste")
			(roundrect_rratio 0.25)
			(net 417 "GND")
			(pintype "passive")
		)
		(pad "2" smd roundrect
			(at 0.48 0 90)
			(size 0.59 0.64)
			(layers "B.Cu" "B.Mask" "B.Paste")
			(roundrect_rratio 0.25)
			(net 50 "+3V3")
			(pintype "passive")
		)
	)
	(footprint "antmicro-footprints:C_0603_1608Metric"
		(layer "B.Cu")
		(at 201.8 133.9 180)
		(descr "Capacitor SMD 0603")
		(tags "capacitor 0603")
		(property "Reference" "C233"
			(at -1.4 0.7 0)
			(layer "B.SilkS")
			(effects
				(font
					(size 0.7 0.7)
					(thickness 0.15)
				)
				(justify left bottom mirror)
			)
		)
		(property "Value" "C_47u_0603"
			(at -1.42757 -1.770288 0)
			(layer "B.Fab")
			(hide yes)
			(effects
				(font
					(size 0.7 0.7)
					(thickness 0.15)
				)
				(justify left bottom mirror)
			)
		)
		(property "Datasheet" "https://www.murata.com/products/productdetail?partno=GRM188R60J476ME15%23"
			(at 0 0 180)
			(layer "F.Fab")
			(hide yes)
			(effects
				(font
					(size 1.27 1.27)
					(thickness 0.15)
				)
			)
		)
		(property "Description" "SMD Multilayer Ceramic Capacitor, 47 µF, 6.3 V, 0603 [1608 Metric], ± 20%, X5R, GRM Series"
			(at 0 0 180)
			(layer "F.Fab")
			(hide yes)
			(effects
				(font
					(size 1.27 1.27)
					(thickness 0.15)
				)
			)
		)
		(property "Author" "Antmicro"
			(at 403.6 267.8 0)
			(layer "B.Fab")
			(hide yes)
			(effects
				(font
					(size 1 1)
					(thickness 0.15)
				)
				(justify mirror)
			)
		)
		(property "Capacitance" "47u"
			(at 403.6 267.8 0)
			(layer "B.Fab")
			(hide yes)
			(effects
				(font
					(size 1 1)
					(thickness 0.15)
				)
				(justify mirror)
			)
		)
		(property "Dielectric" "X7R"
			(at 403.6 267.8 0)
			(layer "B.Fab")
			(hide yes)
			(effects
				(font
					(size 1 1)
					(thickness 0.15)
				)
				(justify mirror)
			)
		)
		(property "License" "Apache-2.0"
			(at 403.6 267.8 0)
			(layer "B.Fab")
			(hide yes)
			(effects
				(font
					(size 1 1)
					(thickness 0.15)
				)
				(justify mirror)
			)
		)
		(property "MPN" "GRM188R60J476ME15D"
			(at 403.6 267.8 0)
			(layer "B.Fab")
			(hide yes)
			(effects
				(font
					(size 1 1)
					(thickness 0.15)
				)
				(justify mirror)
			)
		)
		(property "Manufacturer" "Murata"
			(at 403.6 267.8 0)
			(layer "B.Fab")
			(hide yes)
			(effects
				(font
					(size 1 1)
					(thickness 0.15)
				)
				(justify mirror)
			)
		)
		(property "Public" ""
			(at 403.6 267.8 0)
			(layer "B.Fab")
			(hide yes)
			(effects
				(font
					(size 1 1)
					(thickness 0.15)
				)
				(justify mirror)
			)
		)
		(property "Val" "47u"
			(at 403.6 267.8 0)
			(layer "B.Fab")
			(hide yes)
			(effects
				(font
					(size 1 1)
					(thickness 0.15)
				)
				(justify mirror)
			)
		)
		(property "Voltage" "50V"
			(at 403.6 267.8 0)
			(layer "B.Fab")
			(hide yes)
			(effects
				(font
					(size 1 1)
					(thickness 0.15)
				)
				(justify mirror)
			)
		)
		(sheetname "/FPGA Supply/")
		(sheetfile "fpga-supply.kicad_sch")
		(attr smd)
		(fp_line
			(start -0.15 0.4)
			(end 0.15 0.4)
			(stroke
				(width 0.15)
				(type solid)
			)
			(layer "B.SilkS")
		)
		(fp_line
			(start -0.15 -0.4)
			(end 0.15 -0.4)
			(stroke
				(width 0.15)
				(type solid)
			)
			(layer "B.SilkS")
		)
		(fp_rect
			(start -1.25 0.65)
			(end 1.25 -0.65)
			(stroke
				(width 0.05)
				(type solid)
			)
			(fill no)
			(layer "B.CrtYd")
		)
		(fp_rect
			(start -0.8 0.4)
			(end 0.8 -0.4)
			(stroke
				(width 0.15)
				(type solid)
			)
			(fill no)
			(layer "B.Fab")
		)
		(fp_text user "License: Apache-2.0"
			(at -1.682 -5.895 0)
			(layer "B.Fab")
			(effects
				(font
					(size 0.7 0.7)
					(thickness 0.15)
				)
				(justify left bottom mirror)
			)
		)
		(fp_text user "${REFERENCE}"
			(at -1.682 -3.895 0)
			(layer "B.Fab")
			(effects
				(font
					(size 0.7 0.7)
					(thickness 0.15)
				)
				(justify left bottom mirror)
			)
		)
		(fp_text user "Author: Antmicro"
			(at -1.682 -4.894 0)
			(layer "B.Fab")
			(effects
				(font
					(size 0.7 0.7)
					(thickness 0.15)
				)
				(justify left bottom mirror)
			)
		)
		(pad "1" smd roundrect
			(at -0.7 0 180)
			(size 0.8 1)
			(layers "B.Cu" "B.Mask" "B.Paste")
			(roundrect_rratio 0.2)
			(net 417 "GND")
			(pintype "passive")
		)
		(pad "2" smd roundrect
			(at 0.7 0 180)
			(size 0.8 1)
			(layers "B.Cu" "B.Mask" "B.Paste")
			(roundrect_rratio 0.2)
			(net 49 "VDDAUX")
			(pintype "passive")
		)
	)
	(footprint "antmicro-footprints:C_0402_1005Metric"
		(layer "B.Cu")
		(at 208.116 145.5 180)
		(descr "Capacitor SMD 0402")
		(tags "capacitor SMD 0402")
		(property "Reference" "C206"
			(at 5.716 18.35 0)
			(layer "B.SilkS")
			(effects
				(font
					(size 0.7 0.7)
					(thickness 0.15)
				)
				(justify left bottom mirror)
			)
		)
		(property "Value" "C_100n_0402"
			(at -1.022927 -2.155213 0)
			(layer "B.Fab")
			(hide yes)
			(effects
				(font
					(size 0.7 0.7)
					(thickness 0.15)
				)
				(justify left bottom mirror)
			)
		)
		(property "Datasheet" "https://www.murata.com/products/productdetail?partno=GRM155R61H104KE14%23"
			(at 0 0 180)
			(layer "F.Fab")
			(hide yes)
			(effects
				(font
					(size 1.27 1.27)
					(thickness 0.15)
				)
			)
		)
		(property "Description" "SMD Multilayer Ceramic Capacitor, 0.1 µF, 50 V, 0402 [1005 Metric], ± 10%, X5R, GRM Series"
			(at 0 0 180)
			(layer "F.Fab")
			(hide yes)
			(effects
				(font
					(size 1.27 1.27)
					(thickness 0.15)
				)
			)
		)
		(property "Author" "Antmicro"
			(at 416.232 291 0)
			(layer "B.Fab")
			(hide yes)
			(effects
				(font
					(size 1 1)
					(thickness 0.15)
				)
				(justify mirror)
			)
		)
		(property "Dielectric" "X5R"
			(at 416.232 291 0)
			(layer "B.Fab")
			(hide yes)
			(effects
				(font
					(size 1 1)
					(thickness 0.15)
				)
				(justify mirror)
			)
		)
		(property "License" "Apache-2.0"
			(at 416.232 291 0)
			(layer "B.Fab")
			(hide yes)
			(effects
				(font
					(size 1 1)
					(thickness 0.15)
				)
				(justify mirror)
			)
		)
		(property "MPN" "GRM155R61H104KE14D"
			(at 416.232 291 0)
			(layer "B.Fab")
			(hide yes)
			(effects
				(font
					(size 1 1)
					(thickness 0.15)
				)
				(justify mirror)
			)
		)
		(property "Manufacturer" "Murata"
			(at 416.232 291 0)
			(layer "B.Fab")
			(hide yes)
			(effects
				(font
					(size 1 1)
					(thickness 0.15)
				)
				(justify mirror)
			)
		)
		(property "Public" ""
			(at 416.232 291 0)
			(layer "B.Fab")
			(hide yes)
			(effects
				(font
					(size 1 1)
					(thickness 0.15)
				)
				(justify mirror)
			)
		)
		(property "Val" "100n"
			(at 416.232 291 0)
			(layer "B.Fab")
			(hide yes)
			(effects
				(font
					(size 1 1)
					(thickness 0.15)
				)
				(justify mirror)
			)
		)
		(property "Voltage" "50V"
			(at 416.232 291 0)
			(layer "B.Fab")
			(hide yes)
			(effects
				(font
					(size 1 1)
					(thickness 0.15)
				)
				(justify mirror)
			)
		)
		(sheetname "/MIPI CrossLink/")
		(sheetfile "crosslink.kicad_sch")
		(attr smd)
		(fp_rect
			(start -0.925 0.47)
			(end 0.925 -0.47)
			(stroke
				(width 0.05)
				(type default)
			)
			(fill no)
			(layer "B.CrtYd")
		)
		(fp_line
			(start 0.504 0.25)
			(end 0.504 -0.248)
			(stroke
				(width 0.15)
				(type solid)
			)
			(layer "B.Fab")
		)
		(fp_line
			(start 0.504 -0.248)
			(end -0.494 -0.248)
			(stroke
				(width 0.15)
				(type solid)
			)
			(layer "B.Fab")
		)
		(fp_line
			(start -0.494 0.25)
			(end 0.504 0.25)
			(stroke
				(width 0.15)
				(type solid)
			)
			(layer "B.Fab")
		)
		(fp_line
			(start -0.494 -0.248)
			(end -0.494 0.25)
			(stroke
				(width 0.15)
				(type solid)
			)
			(layer "B.Fab")
		)
		(fp_text user "License: Apache-2.0"
			(at -0.939 -5.799 0)
			(layer "B.Fab")
			(effects
				(font
					(size 0.7 0.7)
					(thickness 0.15)
				)
				(justify left bottom mirror)
			)
		)
		(fp_text user "${REFERENCE}"
			(at -0.939 -4.599 0)
			(layer "B.Fab")
			(effects
				(font
					(size 0.7 0.7)
					(thickness 0.15)
				)
				(justify left bottom mirror)
			)
		)
		(fp_text user "Author: Antmicro"
			(at -0.939 -3.399 0)
			(layer "B.Fab")
			(effects
				(font
					(size 0.7 0.7)
					(thickness 0.15)
				)
				(justify left bottom mirror)
			)
		)
		(pad "1" smd roundrect
			(at -0.48 0 180)
			(size 0.59 0.64)
			(layers "B.Cu" "B.Mask" "B.Paste")
			(roundrect_rratio 0.25)
			(net 417 "GND")
			(pintype "passive")
		)
		(pad "2" smd roundrect
			(at 0.48 0 180)
			(size 0.59 0.64)
			(layers "B.Cu" "B.Mask" "B.Paste")
			(roundrect_rratio 0.25)
			(net 185 "/MIPI CrossLink/CL_VCCIO1")
			(pintype "passive")
		)
	)
	(footprint "antmicro-footprints:TP_SMD_0.75mm"
		(layer "B.Cu")
		(at 204.9 125.2 180)
		(property "Reference" "TP36"
			(at -1.96 -0.36 180)
			(layer "B.SilkS")
			(hide yes)
			(effects
				(font
					(size 0.65 0.65)
					(thickness 0.15)
				)
				(justify left bottom mirror)
			)
		)
		(property "Value" "TP_0.75mm_SMD"
			(at 0 -1.2 0)
			(layer "B.Fab")
			(hide yes)
			(effects
				(font
					(size 0.7 0.7)
					(thickness 0.15)
				)
				(justify left bottom mirror)
			)
		)
		(property "Description" "SMT test point"
			(at 0 0 0)
			(layer "B.Fab")
			(hide yes)
			(effects
				(font
					(size 1.27 1.27)
					(thickness 0.15)
				)
				(justify mirror)
			)
		)
		(property "MPN" ""
			(at 0 0 0)
			(unlocked yes)
			(layer "B.Fab")
			(hide yes)
			(effects
				(font
					(size 1 1)
					(thickness 0.15)
				)
				(justify mirror)
			)
		)
		(property "Manufacturer" ""
			(at 0 0 0)
			(unlocked yes)
			(layer "B.Fab")
			(hide yes)
			(effects
				(font
					(size 1 1)
					(thickness 0.15)
				)
				(justify mirror)
			)
		)
		(property "Author" "Antmicro"
			(at 0 0 0)
			(unlocked yes)
			(layer "B.Fab")
			(hide yes)
			(effects
				(font
					(size 1 1)
					(thickness 0.15)
				)
				(justify mirror)
			)
		)
		(property "License" "Apache-2.0"
			(at 0 0 0)
			(unlocked yes)
			(layer "B.Fab")
			(hide yes)
			(effects
				(font
					(size 1 1)
					(thickness 0.15)
				)
				(justify mirror)
			)
		)
		(property "Public" "False"
			(at 0 0 0)
			(unlocked yes)
			(layer "B.Fab")
			(hide yes)
			(effects
				(font
					(size 1 1)
					(thickness 0.15)
				)
				(justify mirror)
			)
		)
		(sheetname "/Supply/")
		(sheetfile "supply.kicad_sch")
		(attr exclude_from_pos_files exclude_from_bom)
		(fp_circle
			(center 0 0)
			(end 0.475 0)
			(stroke
				(width 0.05)
				(type default)
			)
			(fill no)
			(layer "B.CrtYd")
		)
		(fp_text user "Author: Antmicro"
			(at -0.4 -3.901 0)
			(layer "B.Fab")
			(effects
				(font
					(size 0.7 0.7)
					(thickness 0.15)
				)
				(justify left bottom mirror)
			)
		)
		(fp_text user "License: Apache-2.0"
			(at -0.4 -5.101 0)
			(layer "B.Fab")
			(effects
				(font
					(size 0.7 0.7)
					(thickness 0.15)
				)
				(justify left bottom mirror)
			)
		)
		(fp_text user "${REFERENCE}"
			(at -0.4 -2.7 0)
			(layer "B.Fab")
			(effects
				(font
					(size 0.7 0.7)
					(thickness 0.15)
				)
				(justify left bottom mirror)
			)
		)
		(pad "1" smd circle
			(at 0 0 180)
			(size 0.75 0.75)
			(layers "B.Cu" "B.Mask")
			(net 100 "/FPGA MSSIO/SUPPLY.SDA")
			(pinfunction "1")
			(pintype "passive")
		)
	)
)
